# BASEBOARD_FAB2 (Tioga Pass) — schematic netlist excerpt (pin names and nets, part order shuffled) for the footprints in the layout excerpt that follows; sources: Cadence DE-HDL packaged netlist, KiCad conversion of Wiwynn_Tioga_Pass_MB.brd

R1W35  RES  49.9 1% EMPTY  pkg 0402  page 152 : A = PVCCIO_CPU0 ; B = P0V7_GTL2014_2
FB25W5  BLM15AG121SN-1GP  pkg DISCRET-G  page 254 : \1\ = XDP_TMS_R ; \2\ = XDP_TMS
C4W4  CAP  220PF 50V 10% X7R  pkg 0402LF  page 235 : A = A_TSENSE_P1V05_PCH_STBY_TMON ; B = GND

(kicad_pcb
	(version 20260206)
	(generator "pcbnew")
	(generator_version "10.0")
	(general
		(thickness 1.6)
		(legacy_teardrops no)
	)
	(paper "A4")
	(title_block
		(title "Wiwynn_Tioga_Pass_MB.brd")
		(comment 1 "Tioga Pass / footprints 4521-4523 of 4770")
	)
	(layers
		(0 "F.Cu" signal "TOP")
		(4 "In1.Cu" signal "L2GND")
		(6 "In2.Cu" signal "L3")
		(8 "In3.Cu" signal "L4GND")
		(10 "In4.Cu" signal "L5")
		(12 "In5.Cu" signal "L6GND")
		(14 "In6.Cu" signal "L7VCC")
		(16 "In7.Cu" signal "L8VCC")
		(18 "In8.Cu" signal "L9GND")
		(20 "In9.Cu" signal "L10")
		(22 "In10.Cu" signal "L11GND")
		(24 "In11.Cu" signal "L12")
		(26 "In12.Cu" signal "L13GND")
		(2 "B.Cu" signal "BOTTOM")
		(9 "F.Adhes" user "F.Adhesive")
		(11 "B.Adhes" user "B.Adhesive")
		(13 "F.Paste" user "Package Geometry/Pastemask Top")
		(15 "B.Paste" user "Package Geometry/Pastemask Bottom")
		(5 "F.SilkS" user "Ref Des/Silkscreen Top")
		(7 "B.SilkS" user "Ref Des/Silkscreen Bottom")
		(1 "F.Mask" user "Board Geometry/Soldermask Top")
		(3 "B.Mask" user "Board Geometry/Soldermask Bottom")
		(17 "Dwgs.User" user "User.Drawings")
		(19 "Cmts.User" user "User.Comments")
		(21 "Eco1.User" user "User.Eco1")
		(23 "Eco2.User" user "User.Eco2")
		(25 "Edge.Cuts" user "Board Geometry/Outline")
		(27 "Margin" user)
		(31 "F.CrtYd" user "Package Geometry/Place Bound Top")
		(29 "B.CrtYd" user "Package Geometry/Place Bound Bottom")
		(35 "F.Fab" user "Ref Des/Assembly Top")
		(33 "B.Fab" user "Ref Des/Assembly Bottom")
	)
	(footprint ""
		(layer "B.Cu")
		(at 390.5758 -154.278838 180)
		(property "Reference" "C4W4"
			(at 0.8382 -0.67818 180)
			(unlocked yes)
			(layer "B.SilkS")
			(effects
				(font
					(size 0.4064 0.254)
					(thickness 0.1524)
				)
				(justify left mirror)
			)
		)
		(property "Value" ""
			(at 0 0 0)
			(layer "B.Fab")
			(effects
				(font
					(size 1.27 1.27)
				)
				(justify mirror)
			)
		)
		(duplicate_pad_numbers_are_jumpers no)
		(fp_poly
			(pts
				(xy -0.3048 -0.1016) (xy -0.3048 0.9906) (xy 0.3048 0.9906) (xy 0.3048 -0.1016)
			)
			(stroke
				(width 0)
				(type default)
			)
			(fill no)
			(layer "B.CrtYd")
		)
		(fp_line
			(start 0.3048 0.9906)
			(end -0.3048 0.9906)
			(stroke
				(width 0.1)
				(type default)
			)
			(layer "B.Fab")
		)
		(fp_line
			(start 0.3048 -0.1016)
			(end 0.3048 0.9906)
			(stroke
				(width 0.1)
				(type default)
			)
			(layer "B.Fab")
		)
		(fp_line
			(start -0.3048 0.9906)
			(end -0.3048 -0.1016)
			(stroke
				(width 0.1)
				(type default)
			)
			(layer "B.Fab")
		)
		(fp_line
			(start -0.3048 -0.1016)
			(end 0.3048 -0.1016)
			(stroke
				(width 0.1)
				(type default)
			)
			(layer "B.Fab")
		)
		(pad "1" smd rect
			(at 0 0)
			(size 0.508 0.508)
			(layers "B.Cu" "B.Mask" "B.Paste")
			(net "A_TSENSE_P1V05_PCH_STBY_TMON")
		)
		(pad "2" smd rect
			(at 0 0.889)
			(size 0.508 0.508)
			(layers "B.Cu" "B.Mask" "B.Paste")
			(net "GND")
		)
		(zone
			(layer "B.Cu")
			(hatch none 0.5)
			(connect_pads
				(clearance 0)
			)
			(min_thickness 0.25)
			(keepout
				(tracks not_allowed)
				(vias allowed)
				(pads allowed)
				(copperpour not_allowed)
				(footprints allowed)
			)
			(placement
				(enabled no)
				(sheetname "")
			)
			(fill
				(thermal_gap 0.5)
				(thermal_bridge_width 0.5)
				(island_removal_mode 0)
			)
			(polygon
				(pts
					(xy 390.3218 -154.913838) (xy 390.8298 -154.913838) (xy 390.8298 -154.532838) (xy 390.3218 -154.532838)
				)
			)
		)
		(zone
			(layer "B.Cu")
			(hatch none 0.5)
			(connect_pads
				(clearance 0)
			)
			(min_thickness 0.25)
			(keepout
				(tracks allowed)
				(vias not_allowed)
				(pads allowed)
				(copperpour not_allowed)
				(footprints allowed)
			)
			(placement
				(enabled no)
				(sheetname "")
			)
			(fill
				(thermal_gap 0.5)
				(thermal_bridge_width 0.5)
				(island_removal_mode 0)
			)
			(polygon
				(pts
					(xy 390.3218 -154.532838) (xy 390.8298 -154.532838) (xy 390.8298 -154.913838) (xy 390.3218 -154.913838)
				)
			)
		)
	)
	(footprint ""
		(layer "B.Cu")
		(at 442.722 -14.6812 -90)
		(property "Reference" "R1W35"
			(at 0.8382 -0.67818 270)
			(unlocked yes)
			(layer "B.SilkS")
			(effects
				(font
					(size 0.4064 0.254)
					(thickness 0.1524)
				)
				(justify left mirror)
			)
		)
		(property "Value" ""
			(at 0 0 90)
			(layer "B.Fab")
			(effects
				(font
					(size 1.27 1.27)
				)
				(justify mirror)
			)
		)
		(duplicate_pad_numbers_are_jumpers no)
		(fp_poly
			(pts
				(xy 0.2794 -0.1016) (xy -0.2794 -0.1016) (xy -0.2794 0.9906) (xy 0.2794 0.9906)
			)
			(stroke
				(width 0)
				(type default)
			)
			(fill no)
			(layer "B.CrtYd")
		)
		(fp_line
			(start -0.2794 0.9906)
			(end -0.2794 -0.1016)
			(stroke
				(width 0.1)
				(type default)
			)
			(layer "B.Fab")
		)
		(fp_line
			(start 0.2794 0.9906)
			(end -0.2794 0.9906)
			(stroke
				(width 0.1)
				(type default)
			)
			(layer "B.Fab")
		)
		(fp_line
			(start -0.2794 -0.1016)
			(end 0.2794 -0.1016)
			(stroke
				(width 0.1)
				(type default)
			)
			(layer "B.Fab")
		)
		(fp_line
			(start 0.2794 -0.1016)
			(end 0.2794 0.9906)
			(stroke
				(width 0.1)
				(type default)
			)
			(layer "B.Fab")
		)
		(pad "1" smd rect
			(at 0 0 90)
			(size 0.508 0.508)
			(layers "B.Cu" "B.Mask" "B.Paste")
			(net "PVCCIO_CPU0")
		)
		(pad "2" smd rect
			(at 0 0.889 90)
			(size 0.508 0.508)
			(layers "B.Cu" "B.Mask" "B.Paste")
			(net "P0V7_GTL2014_2")
		)
		(zone
			(layer "B.Cu")
			(hatch none 0.5)
			(connect_pads
				(clearance 0)
			)
			(min_thickness 0.25)
			(keepout
				(tracks not_allowed)
				(vias allowed)
				(pads allowed)
				(copperpour not_allowed)
				(footprints allowed)
			)
			(placement
				(enabled no)
				(sheetname "")
			)
			(fill
				(thermal_gap 0.5)
				(thermal_bridge_width 0.5)
				(island_removal_mode 0)
			)
			(polygon
				(pts
					(xy 442.087 -14.4272) (xy 442.087 -14.9352) (xy 442.468 -14.9352) (xy 442.468 -14.4272)
				)
			)
		)
		(zone
			(layer "B.Cu")
			(hatch none 0.5)
			(connect_pads
				(clearance 0)
			)
			(min_thickness 0.25)
			(keepout
				(tracks allowed)
				(vias not_allowed)
				(pads allowed)
				(copperpour not_allowed)
				(footprints allowed)
			)
			(placement
				(enabled no)
				(sheetname "")
			)
			(fill
				(thermal_gap 0.5)
				(thermal_bridge_width 0.5)
				(island_removal_mode 0)
			)
			(polygon
				(pts
					(xy 442.468 -14.4272) (xy 442.468 -14.9352) (xy 442.087 -14.9352) (xy 442.087 -14.4272)
				)
			)
		)
	)
	(footprint ""
		(layer "B.Cu")
		(at 450.8627 -145.21053 -90)
		(property "Reference" "FB25W5"
			(at 0 0 90)
			(layer "B.SilkS")
			(hide yes)
			(effects
				(font
					(size 1.27 1.27)
				)
				(justify mirror)
			)
		)
		(property "Value" "*"
			(at 0.0127 -7.01675 270)
			(unlocked yes)
			(layer "B.Fab")
			(hide yes)
			(effects
				(font
					(size 0.889 0.889)
					(thickness 0.1524)
				)
				(justify mirror)
			)
		)
		(property "Device Type" "BLM15AG121SN-1GP_DISCRET-G-BLMA"
			(at 0.0127 -8.54075 270)
			(unlocked yes)
			(layer "B.Fab")
			(hide yes)
			(effects
				(font
					(size 0.889 0.889)
					(thickness 0.1524)
				)
				(justify mirror)
			)
		)
		(duplicate_pad_numbers_are_jumpers no)
		(fp_line
			(start 0.508 0.9398)
			(end 0.508 0.8636)
			(stroke
				(width 0.1524)
				(type default)
			)
			(layer "B.SilkS")
		)
		(fp_line
			(start -0.508 -0.9398)
			(end 0.508 -0.9398)
			(stroke
				(width 0.1524)
				(type default)
			)
			(layer "B.SilkS")
		)
		(fp_line
			(start 0.508 -0.9398)
			(end 0.508 0.9398)
			(stroke
				(width 0.1524)
				(type default)
			)
			(layer "B.SilkS")
		)
		(fp_rect
			(start 0.508 0.9398)
			(end -0.508 -0.9398)
			(stroke
				(width 0)
				(type default)
			)
			(fill no)
			(layer "B.CrtYd")
		)
		(fp_rect
			(start 0.508 0.9398)
			(end -0.508 -0.9398)
			(stroke
				(width 0)
				(type default)
			)
			(fill no)
			(layer "B.Fab")
		)
		(pad "1" smd custom
			(at 0 -0.4445 90)
			(size 0.1397 0.1397)
			(layers "B.Cu" "B.Mask" "B.Paste")
			(net "XDP_TMS_R")
			(options
				(clearance outline)
				(anchor circle)
			)
			(primitives
				(gr_poly
					(pts
						(arc
							(start -0.1778 0.2794)
							(mid -0.249642 0.249642)
							(end -0.2794 0.1778)
						)
						(arc
							(start -0.2794 -0.1778)
							(mid -0.249642 -0.249642)
							(end -0.1778 -0.2794)
						)
						(arc
							(start 0.1778 -0.2794)
							(mid 0.249642 -0.249642)
							(end 0.2794 -0.1778)
						)
						(arc
							(start 0.2794 0.1778)
							(mid 0.249642 0.249642)
							(end 0.1778 0.2794)
						)
					)
					(width 0)
					(fill yes)
				)
			)
		)
		(pad "2" smd custom
			(at 0 0.4445 90)
			(size 0.1397 0.1397)
			(layers "B.Cu" "B.Mask" "B.Paste")
			(net "XDP_TMS")
			(options
				(clearance outline)
				(anchor circle)
			)
			(primitives
				(gr_poly
					(pts
						(arc
							(start -0.1778 0.2794)
							(mid -0.249642 0.249642)
							(end -0.2794 0.1778)
						)
						(arc
							(start -0.2794 -0.1778)
							(mid -0.249642 -0.249642)
							(end -0.1778 -0.2794)
						)
						(arc
							(start 0.1778 -0.2794)
							(mid 0.249642 -0.249642)
							(end 0.2794 -0.1778)
						)
						(arc
							(start 0.2794 0.1778)
							(mid 0.249642 0.249642)
							(end 0.1778 0.2794)
						)
					)
					(width 0)
					(fill yes)
				)
			)
		)
	)
)
